(kicad_pcb
	(version 20260206)
	(generator "pcbnew")
	(generator_version "10.0")
	(general
		(thickness 1.6)
		(legacy_teardrops no)
	)
	(paper "A4")
	(title_block
		(title "04192023_DAF0TMB3IC0_F0TG_MB_C_brd_V02_OCP.brd")
		(comment 1 "Grand Teton / footprints 3054-3059 of 8354")
	)
	(layers
		(0 "F.Cu" signal "TOP")
		(4 "In1.Cu" signal "GND")
		(6 "In2.Cu" signal "IN1")
		(8 "In3.Cu" signal "GND1")
		(10 "In4.Cu" signal "IN2")
		(12 "In5.Cu" signal "GND2")
		(14 "In6.Cu" signal "IN3")
		(16 "In7.Cu" signal "GND3")
		(18 "In8.Cu" signal "VCC")
		(20 "In9.Cu" signal "VCC1")
		(22 "In10.Cu" signal "GND4")
		(24 "In11.Cu" signal "IN4")
		(26 "In12.Cu" signal "GND5")
		(28 "In13.Cu" signal "IN5")
		(30 "In14.Cu" signal "GND6")
		(32 "In15.Cu" signal "IN6")
		(34 "In16.Cu" signal "GND7")
		(2 "B.Cu" signal "BOTTOM")
		(9 "F.Adhes" user "F.Adhesive")
		(11 "B.Adhes" user "B.Adhesive")
		(13 "F.Paste" user "Package Geometry/Pastemask Top")
		(15 "B.Paste" user "Package Geometry/Pastemask Bottom")
		(5 "F.SilkS" user "Ref Des/Silkscreen Top")
		(7 "B.SilkS" user "Ref Des/Silkscreen Bottom")
		(1 "F.Mask" user "Board Geometry/Soldermask Top")
		(3 "B.Mask" user "Board Geometry/Soldermask Bottom")
		(17 "Dwgs.User" user "User.Drawings")
		(19 "Cmts.User" user "User.Comments")
		(21 "Eco1.User" user "User.Eco1")
		(23 "Eco2.User" user "User.Eco2")
		(25 "Edge.Cuts" user "Board Geometry/Outline")
		(27 "Margin" user)
		(31 "F.CrtYd" user "Package Geometry/Place Bound Top")
		(29 "B.CrtYd" user "Package Geometry/Place Bound Bottom")
		(35 "F.Fab" user "Ref Des/Assembly Top")
		(33 "B.Fab" user "Ref Des/Assembly Bottom")
	)
	(footprint ""
		(layer "F.Cu")
		(at 89.567512 -72.46366 90)
		(property "Reference" "PC2168"
			(at 0 0 90)
			(layer "F.SilkS")
			(hide yes)
			(effects
				(font
					(size 1.27 1.27)
				)
			)
		)
		(property "Value" ""
			(at 0 0 90)
			(layer "F.Fab")
			(effects
				(font
					(size 1.27 1.27)
				)
			)
		)
		(duplicate_pad_numbers_are_jumpers no)
		(fp_line
			(start 0.7874 -0.4064)
			(end 0.7874 0.4064)
			(stroke
				(width 0.1524)
				(type default)
			)
			(layer "F.SilkS")
		)
		(fp_line
			(start -0.7874 -0.4064)
			(end 0.7874 -0.4064)
			(stroke
				(width 0.1524)
				(type default)
			)
			(layer "F.SilkS")
		)
		(fp_line
			(start 0.7874 0.4064)
			(end -0.7874 0.4064)
			(stroke
				(width 0.1524)
				(type default)
			)
			(layer "F.SilkS")
		)
		(fp_line
			(start -0.7874 0.4064)
			(end -0.7874 -0.4064)
			(stroke
				(width 0.1524)
				(type default)
			)
			(layer "F.SilkS")
		)
		(fp_line
			(start -0.12065 -0.305054)
			(end -0.12065 -0.2794)
			(stroke
				(width 0.1)
				(type default)
			)
			(layer "F.Fab")
		)
		(fp_line
			(start -0.67945 -0.305054)
			(end -0.12065 -0.305054)
			(stroke
				(width 0.1)
				(type default)
			)
			(layer "F.Fab")
		)
		(fp_line
			(start 0.67945 -0.3048)
			(end 0.67945 0.3048)
			(stroke
				(width 0.1)
				(type default)
			)
			(layer "F.Fab")
		)
		(fp_line
			(start 0.12065 -0.3048)
			(end 0.67945 -0.3048)
			(stroke
				(width 0.1)
				(type default)
			)
			(layer "F.Fab")
		)
		(fp_line
			(start 0.12065 -0.2794)
			(end 0.12065 -0.3048)
			(stroke
				(width 0.1)
				(type default)
			)
			(layer "F.Fab")
		)
		(fp_line
			(start -0.12065 -0.2794)
			(end 0.12065 -0.2794)
			(stroke
				(width 0.1)
				(type default)
			)
			(layer "F.Fab")
		)
		(fp_line
			(start 0.120396 0.2794)
			(end -0.12065 0.2794)
			(stroke
				(width 0.1)
				(type default)
			)
			(layer "F.Fab")
		)
		(fp_line
			(start -0.12065 0.2794)
			(end -0.12065 0.3048)
			(stroke
				(width 0.1)
				(type default)
			)
			(layer "F.Fab")
		)
		(fp_line
			(start 0.67945 0.3048)
			(end 0.120396 0.3048)
			(stroke
				(width 0.1)
				(type default)
			)
			(layer "F.Fab")
		)
		(fp_line
			(start 0.120396 0.3048)
			(end 0.120396 0.2794)
			(stroke
				(width 0.1)
				(type default)
			)
			(layer "F.Fab")
		)
		(fp_line
			(start -0.12065 0.3048)
			(end -0.67945 0.3048)
			(stroke
				(width 0.1)
				(type default)
			)
			(layer "F.Fab")
		)
		(fp_line
			(start -0.67945 0.3048)
			(end -0.67945 -0.305054)
			(stroke
				(width 0.1)
				(type default)
			)
			(layer "F.Fab")
		)
		(pad "1" smd circle
			(at -0.40005 0 90)
			(size 0 0)
			(layers "F.Cu" "F.Mask" "F.Paste")
			(net "P3V3_OCP_MODE_2")
		)
		(pad "2" smd circle
			(at 0.40005 0 90)
			(size 0 0)
			(layers "F.Cu" "F.Mask" "F.Paste")
			(net "GND")
		)
	)
	(footprint ""
		(layer "F.Cu")
		(at 36.837112 -368.455448 90)
		(property "Reference" "PC365"
			(at 0 0 90)
			(layer "F.SilkS")
			(hide yes)
			(effects
				(font
					(size 1.27 1.27)
				)
			)
		)
		(property "Value" ""
			(at 0 0 90)
			(layer "F.Fab")
			(effects
				(font
					(size 1.27 1.27)
				)
			)
		)
		(duplicate_pad_numbers_are_jumpers no)
		(fp_line
			(start 0.7874 -0.4064)
			(end 0.7874 0.4064)
			(stroke
				(width 0.1524)
				(type default)
			)
			(layer "F.SilkS")
		)
		(fp_line
			(start -0.7874 -0.4064)
			(end 0.7874 -0.4064)
			(stroke
				(width 0.1524)
				(type default)
			)
			(layer "F.SilkS")
		)
		(fp_line
			(start 0.7874 0.4064)
			(end -0.7874 0.4064)
			(stroke
				(width 0.1524)
				(type default)
			)
			(layer "F.SilkS")
		)
		(fp_line
			(start -0.7874 0.4064)
			(end -0.7874 -0.4064)
			(stroke
				(width 0.1524)
				(type default)
			)
			(layer "F.SilkS")
		)
		(fp_line
			(start -0.12065 -0.305054)
			(end -0.12065 -0.2794)
			(stroke
				(width 0.1)
				(type default)
			)
			(layer "F.Fab")
		)
		(fp_line
			(start -0.67945 -0.305054)
			(end -0.12065 -0.305054)
			(stroke
				(width 0.1)
				(type default)
			)
			(layer "F.Fab")
		)
		(fp_line
			(start 0.67945 -0.3048)
			(end 0.67945 0.3048)
			(stroke
				(width 0.1)
				(type default)
			)
			(layer "F.Fab")
		)
		(fp_line
			(start 0.12065 -0.3048)
			(end 0.67945 -0.3048)
			(stroke
				(width 0.1)
				(type default)
			)
			(layer "F.Fab")
		)
		(fp_line
			(start 0.12065 -0.2794)
			(end 0.12065 -0.3048)
			(stroke
				(width 0.1)
				(type default)
			)
			(layer "F.Fab")
		)
		(fp_line
			(start -0.12065 -0.2794)
			(end 0.12065 -0.2794)
			(stroke
				(width 0.1)
				(type default)
			)
			(layer "F.Fab")
		)
		(fp_line
			(start 0.120396 0.2794)
			(end -0.12065 0.2794)
			(stroke
				(width 0.1)
				(type default)
			)
			(layer "F.Fab")
		)
		(fp_line
			(start -0.12065 0.2794)
			(end -0.12065 0.3048)
			(stroke
				(width 0.1)
				(type default)
			)
			(layer "F.Fab")
		)
		(fp_line
			(start 0.67945 0.3048)
			(end 0.120396 0.3048)
			(stroke
				(width 0.1)
				(type default)
			)
			(layer "F.Fab")
		)
		(fp_line
			(start 0.120396 0.3048)
			(end 0.120396 0.2794)
			(stroke
				(width 0.1)
				(type default)
			)
			(layer "F.Fab")
		)
		(fp_line
			(start -0.12065 0.3048)
			(end -0.67945 0.3048)
			(stroke
				(width 0.1)
				(type default)
			)
			(layer "F.Fab")
		)
		(fp_line
			(start -0.67945 0.3048)
			(end -0.67945 -0.305054)
			(stroke
				(width 0.1)
				(type default)
			)
			(layer "F.Fab")
		)
		(pad "1" smd circle
			(at -0.40005 0 90)
			(size 0 0)
			(layers "F.Cu" "F.Mask" "F.Paste")
			(net "PVDDCR_CPU1_P1_VCC")
		)
		(pad "2" smd circle
			(at 0.40005 0 90)
			(size 0 0)
			(layers "F.Cu" "F.Mask" "F.Paste")
			(net "GND")
		)
	)
	(footprint ""
		(layer "F.Cu")
		(at 322.653152 -34.620962)
		(property "Reference" "U193"
			(at -1.712468 3.20294 0)
			(unlocked yes)
			(layer "F.SilkS")
			(effects
				(font
					(size 0.7874 0.5842)
					(thickness 0.1524)
				)
				(justify left)
			)
		)
		(property "Value" ""
			(at 0 0 0)
			(layer "F.Fab")
			(effects
				(font
					(size 1.27 1.27)
				)
			)
		)
		(duplicate_pad_numbers_are_jumpers no)
		(fp_line
			(start -1.715516 -2.489962)
			(end -1.715516 2.489962)
			(stroke
				(width 0.1524)
				(type default)
			)
			(layer "F.SilkS")
		)
		(fp_line
			(start -1.715516 2.489962)
			(end 1.715516 2.489962)
			(stroke
				(width 0.1524)
				(type default)
			)
			(layer "F.SilkS")
		)
		(fp_line
			(start -1.092962 -2.489962)
			(end -1.715516 -2.489962)
			(stroke
				(width 0.1524)
				(type default)
			)
			(layer "F.SilkS")
		)
		(fp_line
			(start 0 -1.397)
			(end -1.092962 -2.489962)
			(stroke
				(width 0.1524)
				(type default)
			)
			(layer "F.SilkS")
		)
		(fp_line
			(start 1.092962 -2.489962)
			(end 0 -1.397)
			(stroke
				(width 0.1524)
				(type default)
			)
			(layer "F.SilkS")
		)
		(fp_line
			(start 1.715516 -2.489962)
			(end 1.092962 -2.489962)
			(stroke
				(width 0.1524)
				(type default)
			)
			(layer "F.SilkS")
		)
		(fp_line
			(start 1.715516 2.489962)
			(end 1.715516 -2.489962)
			(stroke
				(width 0.1524)
				(type default)
			)
			(layer "F.SilkS")
		)
		(fp_poly
			(pts
				(xy -3.203956 -3.79984) (xy -2.187956 -3.79984) (xy -2.695956 -2.78384)
			)
			(stroke
				(width 0)
				(type default)
			)
			(fill yes)
			(layer "F.SilkS")
		)
		(fp_line
			(start -1.994916 -2.489962)
			(end -1.994916 2.489962)
			(stroke
				(width 0.1)
				(type default)
			)
			(layer "F.Fab")
		)
		(fp_line
			(start -1.994916 2.489962)
			(end 1.994916 2.489962)
			(stroke
				(width 0.1)
				(type default)
			)
			(layer "F.Fab")
		)
		(fp_line
			(start 1.994916 -2.489962)
			(end -1.994916 -2.489962)
			(stroke
				(width 0.1)
				(type default)
			)
			(layer "F.Fab")
		)
		(fp_line
			(start 1.994916 2.489962)
			(end 1.994916 -2.489962)
			(stroke
				(width 0.1)
				(type default)
			)
			(layer "F.Fab")
		)
		(fp_poly
			(pts
				(xy -4.699 -2.7305) (xy -4.699 -1.7145) (xy -3.683 -2.2225)
			)
			(stroke
				(width 0)
				(type default)
			)
			(fill yes)
			(layer "F.Fab")
		)
		(pad "1" smd rect
			(at -2.655062 -2.2225 90)
			(size 0.381 1.6002)
			(layers "F.Cu" "F.Mask" "F.Paste")
			(net "MAX11617_VREF_R")
		)
		(pad "2" smd rect
			(at -2.655062 -1.5875 90)
			(size 0.381 1.6002)
			(layers "F.Cu" "F.Mask" "F.Paste")
			(net "GND")
		)
		(pad "3" smd rect
			(at -2.655062 -0.9525 90)
			(size 0.381 1.6002)
			(layers "F.Cu" "F.Mask" "F.Paste")
			(net "GND")
		)
		(pad "4" smd rect
			(at -2.655062 -0.3175 90)
			(size 0.381 1.6002)
			(layers "F.Cu" "F.Mask" "F.Paste")
			(net "GND")
		)
		(pad "5" smd rect
			(at -2.655062 0.3175 90)
			(size 0.381 1.6002)
			(layers "F.Cu" "F.Mask" "F.Paste")
			(net "P12V_AUX_ADC_MAM")
		)
		(pad "6" smd rect
			(at -2.655062 0.9525 90)
			(size 0.381 1.6002)
			(layers "F.Cu" "F.Mask" "F.Paste")
			(net "P12V_OCP_SFF_ISENSE_MAM")
		)
		(pad "7" smd rect
			(at -2.655062 1.5875 90)
			(size 0.381 1.6002)
			(layers "F.Cu" "F.Mask" "F.Paste")
			(net "P12V_OCP_V3_2_ISENSE_MAM")
		)
		(pad "8" smd rect
			(at -2.655062 2.2225 90)
			(size 0.381 1.6002)
			(layers "F.Cu" "F.Mask" "F.Paste")
			(net "P5V_ADC_MAM")
		)
		(pad "9" smd rect
			(at 2.655062 2.2225 90)
			(size 0.381 1.6002)
			(layers "F.Cu" "F.Mask" "F.Paste")
			(net "P3V3_ADC_MAM")
		)
		(pad "10" smd rect
			(at 2.655062 1.5875 90)
			(size 0.381 1.6002)
			(layers "F.Cu" "F.Mask" "F.Paste")
			(net "P3V3_AUX_ADC_MAM")
		)
		(pad "11" smd rect
			(at 2.655062 0.9525 90)
			(size 0.381 1.6002)
			(layers "F.Cu" "F.Mask" "F.Paste")
			(net "P3V3_PDB_AUX_ADC_MAM")
		)
		(pad "12" smd rect
			(at 2.655062 0.3175 90)
			(size 0.381 1.6002)
			(layers "F.Cu" "F.Mask" "F.Paste")
			(net "P12V_E1S_0_ISENSE_MAM")
		)
		(pad "13" smd rect
			(at 2.655062 -0.3175 90)
			(size 0.381 1.6002)
			(layers "F.Cu" "F.Mask" "F.Paste")
			(net "SMB_SEN_MAM_3V3AUX_SCL")
		)
		(pad "14" smd rect
			(at 2.655062 -0.9525 90)
			(size 0.381 1.6002)
			(layers "F.Cu" "F.Mask" "F.Paste")
			(net "SMB_SEN_MAM_3V3AUX_SDA")
		)
		(pad "15" smd rect
			(at 2.655062 -1.5875 90)
			(size 0.381 1.6002)
			(layers "F.Cu" "F.Mask" "F.Paste")
			(net "GND")
		)
		(pad "16" smd rect
			(at 2.655062 -2.2225 90)
			(size 0.381 1.6002)
			(layers "F.Cu" "F.Mask" "F.Paste")
			(net "P3V3_MAX11617_VDD")
		)
	)
	(footprint ""
		(layer "F.Cu")
		(at 142.595092 -381.48006 180)
		(property "Reference" "C772"
			(at 0 0 180)
			(layer "F.SilkS")
			(hide yes)
			(effects
				(font
					(size 1.27 1.27)
				)
			)
		)
		(property "Value" ""
			(at 0 0 180)
			(layer "F.Fab")
			(effects
				(font
					(size 1.27 1.27)
				)
			)
		)
		(duplicate_pad_numbers_are_jumpers no)
		(fp_line
			(start 0.299974 0.150114)
			(end -0.299974 0.150114)
			(stroke
				(width 0.1)
				(type default)
			)
			(layer "F.Fab")
		)
		(fp_line
			(start 0.299974 -0.150114)
			(end 0.299974 0.150114)
			(stroke
				(width 0.1)
				(type default)
			)
			(layer "F.Fab")
		)
		(fp_line
			(start -0.299974 0.150114)
			(end -0.299974 -0.150114)
			(stroke
				(width 0.1)
				(type default)
			)
			(layer "F.Fab")
		)
		(fp_line
			(start -0.299974 -0.150114)
			(end 0.299974 -0.150114)
			(stroke
				(width 0.1)
				(type default)
			)
			(layer "F.Fab")
		)
		(pad "1" smd rect
			(at -0.2667 0 180)
			(size 0.3048 0.381)
			(layers "F.Cu" "F.Mask" "F.Paste")
			(net "P5E_CPU1_P2_TX_C_DN<0>")
		)
		(pad "2" smd rect
			(at 0.2667 0 180)
			(size 0.3048 0.381)
			(layers "F.Cu" "F.Mask" "F.Paste")
			(net "P5E_CPU1_P2_TX_DN<0>")
		)
	)
	(footprint ""
		(layer "F.Cu")
		(at 97.288096 -178.0413 90)
		(property "Reference" "PC300"
			(at 0 0 90)
			(layer "F.SilkS")
			(hide yes)
			(effects
				(font
					(size 1.27 1.27)
				)
			)
		)
		(property "Value" ""
			(at 0 0 90)
			(layer "F.Fab")
			(effects
				(font
					(size 1.27 1.27)
				)
			)
		)
		(duplicate_pad_numbers_are_jumpers no)
		(fp_line
			(start 0.7874 -0.4064)
			(end 0.7874 0.4064)
			(stroke
				(width 0.1524)
				(type default)
			)
			(layer "F.SilkS")
		)
		(fp_line
			(start -0.7874 -0.4064)
			(end 0.7874 -0.4064)
			(stroke
				(width 0.1524)
				(type default)
			)
			(layer "F.SilkS")
		)
		(fp_line
			(start 0.7874 0.4064)
			(end -0.7874 0.4064)
			(stroke
				(width 0.1524)
				(type default)
			)
			(layer "F.SilkS")
		)
		(fp_line
			(start -0.7874 0.4064)
			(end -0.7874 -0.4064)
			(stroke
				(width 0.1524)
				(type default)
			)
			(layer "F.SilkS")
		)
		(fp_line
			(start -0.12065 -0.305054)
			(end -0.12065 -0.2794)
			(stroke
				(width 0.1)
				(type default)
			)
			(layer "F.Fab")
		)
		(fp_line
			(start -0.67945 -0.305054)
			(end -0.12065 -0.305054)
			(stroke
				(width 0.1)
				(type default)
			)
			(layer "F.Fab")
		)
		(fp_line
			(start 0.67945 -0.3048)
			(end 0.67945 0.3048)
			(stroke
				(width 0.1)
				(type default)
			)
			(layer "F.Fab")
		)
		(fp_line
			(start 0.12065 -0.3048)
			(end 0.67945 -0.3048)
			(stroke
				(width 0.1)
				(type default)
			)
			(layer "F.Fab")
		)
		(fp_line
			(start 0.12065 -0.2794)
			(end 0.12065 -0.3048)
			(stroke
				(width 0.1)
				(type default)
			)
			(layer "F.Fab")
		)
		(fp_line
			(start -0.12065 -0.2794)
			(end 0.12065 -0.2794)
			(stroke
				(width 0.1)
				(type default)
			)
			(layer "F.Fab")
		)
		(fp_line
			(start 0.120396 0.2794)
			(end -0.12065 0.2794)
			(stroke
				(width 0.1)
				(type default)
			)
			(layer "F.Fab")
		)
		(fp_line
			(start -0.12065 0.2794)
			(end -0.12065 0.3048)
			(stroke
				(width 0.1)
				(type default)
			)
			(layer "F.Fab")
		)
		(fp_line
			(start 0.67945 0.3048)
			(end 0.120396 0.3048)
			(stroke
				(width 0.1)
				(type default)
			)
			(layer "F.Fab")
		)
		(fp_line
			(start 0.120396 0.3048)
			(end 0.120396 0.2794)
			(stroke
				(width 0.1)
				(type default)
			)
			(layer "F.Fab")
		)
		(fp_line
			(start -0.12065 0.3048)
			(end -0.67945 0.3048)
			(stroke
				(width 0.1)
				(type default)
			)
			(layer "F.Fab")
		)
		(fp_line
			(start -0.67945 0.3048)
			(end -0.67945 -0.305054)
			(stroke
				(width 0.1)
				(type default)
			)
			(layer "F.Fab")
		)
		(pad "1" smd circle
			(at -0.40005 0 90)
			(size 0 0)
			(layers "F.Cu" "F.Mask" "F.Paste")
			(net "SW_PVDDCR_CPU0_P1_BOOT3_RC")
		)
		(pad "2" smd circle
			(at 0.40005 0 90)
			(size 0 0)
			(layers "F.Cu" "F.Mask" "F.Paste")
			(net "SW_PVDDCR_CPU0_P1_PH3")
		)
	)
	(footprint ""
		(layer "F.Cu")
		(at 167.132 -119.344948 180)
		(property "Reference" "R638"
			(at 0 0 180)
			(layer "F.SilkS")
			(hide yes)
			(effects
				(font
					(size 1.27 1.27)
				)
			)
		)
		(property "Value" ""
			(at 0 0 180)
			(layer "F.Fab")
			(effects
				(font
					(size 1.27 1.27)
				)
			)
		)
		(duplicate_pad_numbers_are_jumpers no)
		(fp_line
			(start 0.7874 0.4064)
			(end -0.7874 0.4064)
			(stroke
				(width 0.1524)
				(type default)
			)
			(layer "F.SilkS")
		)
		(fp_line
			(start 0.7874 -0.4064)
			(end 0.7874 0.4064)
			(stroke
				(width 0.1524)
				(type default)
			)
			(layer "F.SilkS")
		)
		(fp_line
			(start -0.7874 0.4064)
			(end -0.7874 -0.4064)
			(stroke
				(width 0.1524)
				(type default)
			)
			(layer "F.SilkS")
		)
		(fp_line
			(start -0.7874 -0.4064)
			(end 0.7874 -0.4064)
			(stroke
				(width 0.1524)
				(type default)
			)
			(layer "F.SilkS")
		)
		(fp_line
			(start 0.67945 0.3048)
			(end 0.120396 0.3048)
			(stroke
				(width 0.1)
				(type default)
			)
			(layer "F.Fab")
		)
		(fp_line
			(start 0.67945 -0.3048)
			(end 0.67945 0.3048)
			(stroke
				(width 0.1)
				(type default)
			)
			(layer "F.Fab")
		)
		(fp_line
			(start 0.12065 -0.2794)
			(end 0.12065 -0.3048)
			(stroke
				(width 0.1)
				(type default)
			)
			(layer "F.Fab")
		)
		(fp_line
			(start 0.12065 -0.3048)
			(end 0.67945 -0.3048)
			(stroke
				(width 0.1)
				(type default)
			)
			(layer "F.Fab")
		)
		(fp_line
			(start 0.120396 0.3048)
			(end 0.120396 0.2794)
			(stroke
				(width 0.1)
				(type default)
			)
			(layer "F.Fab")
		)
		(fp_line
			(start 0.120396 0.2794)
			(end -0.12065 0.2794)
			(stroke
				(width 0.1)
				(type default)
			)
			(layer "F.Fab")
		)
		(fp_line
			(start -0.12065 0.3048)
			(end -0.67945 0.3048)
			(stroke
				(width 0.1)
				(type default)
			)
			(layer "F.Fab")
		)
		(fp_line
			(start -0.12065 0.2794)
			(end -0.12065 0.3048)
			(stroke
				(width 0.1)
				(type default)
			)
			(layer "F.Fab")
		)
		(fp_line
			(start -0.12065 -0.2794)
			(end 0.12065 -0.2794)
			(stroke
				(width 0.1)
				(type default)
			)
			(layer "F.Fab")
		)
		(fp_line
			(start -0.12065 -0.305054)
			(end -0.12065 -0.2794)
			(stroke
				(width 0.1)
				(type default)
			)
			(layer "F.Fab")
		)
		(fp_line
			(start -0.67945 0.3048)
			(end -0.67945 -0.305054)
			(stroke
				(width 0.1)
				(type default)
			)
			(layer "F.Fab")
		)
		(fp_line
			(start -0.67945 -0.305054)
			(end -0.12065 -0.305054)
			(stroke
				(width 0.1)
				(type default)
			)
			(layer "F.Fab")
		)
		(pad "1" smd circle
			(at -0.40005 0 180)
			(size 0 0)
			(layers "F.Cu" "F.Mask" "F.Paste")
			(net "CPLD_JTAG_EN")
		)
		(pad "2" smd circle
			(at 0.40005 0 180)
			(size 0 0)
			(layers "F.Cu" "F.Mask" "F.Paste")
			(net "P3V3_AUX")
		)
	)
)
